# S9S_MB_2U (Grand Teton) — schematic netlist excerpt (pin names and nets, part order shuffled) for the footprints in the layout excerpt that follows; sources: Cadence DE-HDL packaged netlist, KiCad conversion of 03242023_DA0F0TMBIJ0_F0T_Motherboard_J_brd_V01_OCP.brd

R3893  Q_RES  49.9 1% CHIP  pkg 0402LF  page 100 : A = I3C_SPD_DDRABCD_CPU1_LVC1_SCL_2 ; B = I3C_SPD_DDRABCD_CPU1_LVC1_SCL
R2498  Q_RES  33.2 1% CHIP  pkg 0402LF  page 115 : A = PWRGD_FAIL_CPU0_AB_R1 ; B = PWRGD_FAIL_CPU0_AB_R

(kicad_pcb
	(version 20260206)
	(generator "pcbnew")
	(generator_version "10.0")
	(general
		(thickness 1.6)
		(legacy_teardrops no)
	)
	(paper "A4")
	(title_block
		(title "03242023_DA0F0TMBIJ0_F0T_Motherboard_J_brd_V01_OCP.brd")
		(comment 1 "Grand Teton / footprints 5234-5235 of 6105")
	)
	(layers
		(0 "F.Cu" signal "TOP")
		(4 "In1.Cu" signal "GND")
		(6 "In2.Cu" signal "IN1")
		(8 "In3.Cu" signal "GND1")
		(10 "In4.Cu" signal "IN2")
		(12 "In5.Cu" signal "GND2")
		(14 "In6.Cu" signal "IN3")
		(16 "In7.Cu" signal "GND3")
		(18 "In8.Cu" signal "VCC")
		(20 "In9.Cu" signal "VCC1")
		(22 "In10.Cu" signal "GND4")
		(24 "In11.Cu" signal "IN4")
		(26 "In12.Cu" signal "GND5")
		(28 "In13.Cu" signal "IN5")
		(30 "In14.Cu" signal "GND6")
		(32 "In15.Cu" signal "IN6")
		(34 "In16.Cu" signal "GND7")
		(2 "B.Cu" signal "BOTTOM")
		(9 "F.Adhes" user "F.Adhesive")
		(11 "B.Adhes" user "B.Adhesive")
		(13 "F.Paste" user "Package Geometry/Pastemask Top")
		(15 "B.Paste" user "Package Geometry/Pastemask Bottom")
		(5 "F.SilkS" user "Ref Des/Silkscreen Top")
		(7 "B.SilkS" user "Ref Des/Silkscreen Bottom")
		(1 "F.Mask" user "Board Geometry/Soldermask Top")
		(3 "B.Mask" user "Board Geometry/Soldermask Bottom")
		(17 "Dwgs.User" user "User.Drawings")
		(19 "Cmts.User" user "User.Comments")
		(21 "Eco1.User" user "User.Eco1")
		(23 "Eco2.User" user "User.Eco2")
		(25 "Edge.Cuts" user "Board Geometry/Outline")
		(27 "Margin" user)
		(31 "F.CrtYd" user "Package Geometry/Place Bound Top")
		(29 "B.CrtYd" user "Package Geometry/Place Bound Bottom")
		(35 "F.Fab" user "Ref Des/Assembly Top")
		(33 "B.Fab" user "Ref Des/Assembly Bottom")
	)
	(footprint ""
		(layer "B.Cu")
		(at 310.843422 -314.550044 90)
		(property "Reference" "R2498"
			(at 0 0 90)
			(layer "B.SilkS")
			(hide yes)
			(effects
				(font
					(size 1.27 1.27)
				)
				(justify mirror)
			)
		)
		(property "Value" ""
			(at 0 0 90)
			(layer "B.Fab")
			(effects
				(font
					(size 1.27 1.27)
				)
				(justify mirror)
			)
		)
		(duplicate_pad_numbers_are_jumpers no)
		(fp_line
			(start 0.7874 -0.4064)
			(end -0.7874 -0.4064)
			(stroke
				(width 0.1524)
				(type default)
			)
			(layer "B.SilkS")
		)
		(fp_line
			(start -0.7874 -0.4064)
			(end -0.7874 0.4064)
			(stroke
				(width 0.1524)
				(type default)
			)
			(layer "B.SilkS")
		)
		(fp_line
			(start 0.7874 0.4064)
			(end 0.7874 -0.4064)
			(stroke
				(width 0.1524)
				(type default)
			)
			(layer "B.SilkS")
		)
		(fp_line
			(start -0.7874 0.4064)
			(end 0.7874 0.4064)
			(stroke
				(width 0.1524)
				(type default)
			)
			(layer "B.SilkS")
		)
		(fp_line
			(start 0.67945 -0.305054)
			(end 0.12065 -0.305054)
			(stroke
				(width 0.1)
				(type default)
			)
			(layer "B.Fab")
		)
		(fp_line
			(start 0.12065 -0.305054)
			(end 0.12065 -0.2794)
			(stroke
				(width 0.1)
				(type default)
			)
			(layer "B.Fab")
		)
		(fp_line
			(start -0.12065 -0.3048)
			(end -0.67945 -0.3048)
			(stroke
				(width 0.1)
				(type default)
			)
			(layer "B.Fab")
		)
		(fp_line
			(start -0.67945 -0.3048)
			(end -0.67945 0.3048)
			(stroke
				(width 0.1)
				(type default)
			)
			(layer "B.Fab")
		)
		(fp_line
			(start 0.12065 -0.2794)
			(end -0.12065 -0.2794)
			(stroke
				(width 0.1)
				(type default)
			)
			(layer "B.Fab")
		)
		(fp_line
			(start -0.12065 -0.2794)
			(end -0.12065 -0.3048)
			(stroke
				(width 0.1)
				(type default)
			)
			(layer "B.Fab")
		)
		(fp_line
			(start 0.12065 0.2794)
			(end 0.12065 0.3048)
			(stroke
				(width 0.1)
				(type default)
			)
			(layer "B.Fab")
		)
		(fp_line
			(start -0.120396 0.2794)
			(end 0.12065 0.2794)
			(stroke
				(width 0.1)
				(type default)
			)
			(layer "B.Fab")
		)
		(fp_line
			(start 0.67945 0.3048)
			(end 0.67945 -0.305054)
			(stroke
				(width 0.1)
				(type default)
			)
			(layer "B.Fab")
		)
		(fp_line
			(start 0.12065 0.3048)
			(end 0.67945 0.3048)
			(stroke
				(width 0.1)
				(type default)
			)
			(layer "B.Fab")
		)
		(fp_line
			(start -0.120396 0.3048)
			(end -0.120396 0.2794)
			(stroke
				(width 0.1)
				(type default)
			)
			(layer "B.Fab")
		)
		(fp_line
			(start -0.67945 0.3048)
			(end -0.120396 0.3048)
			(stroke
				(width 0.1)
				(type default)
			)
			(layer "B.Fab")
		)
		(pad "1" smd circle
			(at 0.40005 0 270)
			(size 0 0)
			(layers "B.Cu" "B.Mask" "B.Paste")
			(net "PWRGD_FAIL_CPU0_AB_R1")
		)
		(pad "2" smd circle
			(at -0.40005 0 270)
			(size 0 0)
			(layers "B.Cu" "B.Mask" "B.Paste")
			(net "PWRGD_FAIL_CPU0_AB_R")
		)
	)
	(footprint ""
		(layer "B.Cu")
		(at 34.003742 -315.557662)
		(property "Reference" "R3893"
			(at 0 0 0)
			(layer "B.SilkS")
			(hide yes)
			(effects
				(font
					(size 1.27 1.27)
				)
				(justify mirror)
			)
		)
		(property "Value" ""
			(at 0 0 0)
			(layer "B.Fab")
			(effects
				(font
					(size 1.27 1.27)
				)
				(justify mirror)
			)
		)
		(duplicate_pad_numbers_are_jumpers no)
		(fp_line
			(start -0.7874 -0.4064)
			(end -0.7874 0.4064)
			(stroke
				(width 0.1524)
				(type default)
			)
			(layer "B.SilkS")
		)
		(fp_line
			(start -0.7874 0.4064)
			(end 0.7874 0.4064)
			(stroke
				(width 0.1524)
				(type default)
			)
			(layer "B.SilkS")
		)
		(fp_line
			(start 0.7874 -0.4064)
			(end -0.7874 -0.4064)
			(stroke
				(width 0.1524)
				(type default)
			)
			(layer "B.SilkS")
		)
		(fp_line
			(start 0.7874 0.4064)
			(end 0.7874 -0.4064)
			(stroke
				(width 0.1524)
				(type default)
			)
			(layer "B.SilkS")
		)
		(fp_line
			(start -0.67945 -0.3048)
			(end -0.67945 0.3048)
			(stroke
				(width 0.1)
				(type default)
			)
			(layer "B.Fab")
		)
		(fp_line
			(start -0.67945 0.3048)
			(end -0.120396 0.3048)
			(stroke
				(width 0.1)
				(type default)
			)
			(layer "B.Fab")
		)
		(fp_line
			(start -0.12065 -0.3048)
			(end -0.67945 -0.3048)
			(stroke
				(width 0.1)
				(type default)
			)
			(layer "B.Fab")
		)
		(fp_line
			(start -0.12065 -0.2794)
			(end -0.12065 -0.3048)
			(stroke
				(width 0.1)
				(type default)
			)
			(layer "B.Fab")
		)
		(fp_line
			(start -0.120396 0.2794)
			(end 0.12065 0.2794)
			(stroke
				(width 0.1)
				(type default)
			)
			(layer "B.Fab")
		)
		(fp_line
			(start -0.120396 0.3048)
			(end -0.120396 0.2794)
			(stroke
				(width 0.1)
				(type default)
			)
			(layer "B.Fab")
		)
		(fp_line
			(start 0.12065 -0.305054)
			(end 0.12065 -0.2794)
			(stroke
				(width 0.1)
				(type default)
			)
			(layer "B.Fab")
		)
		(fp_line
			(start 0.12065 -0.2794)
			(end -0.12065 -0.2794)
			(stroke
				(width 0.1)
				(type default)
			)
			(layer "B.Fab")
		)
		(fp_line
			(start 0.12065 0.2794)
			(end 0.12065 0.3048)
			(stroke
				(width 0.1)
				(type default)
			)
			(layer "B.Fab")
		)
		(fp_line
			(start 0.12065 0.3048)
			(end 0.67945 0.3048)
			(stroke
				(width 0.1)
				(type default)
			)
			(layer "B.Fab")
		)
		(fp_line
			(start 0.67945 -0.305054)
			(end 0.12065 -0.305054)
			(stroke
				(width 0.1)
				(type default)
			)
			(layer "B.Fab")
		)
		(fp_line
			(start 0.67945 0.3048)
			(end 0.67945 -0.305054)
			(stroke
				(width 0.1)
				(type default)
			)
			(layer "B.Fab")
		)
		(pad "1" smd circle
			(at 0.40005 0 180)
			(size 0 0)
			(layers "B.Cu" "B.Mask" "B.Paste")
			(net "I3C_SPD_DDRABCD_CPU1_LVC1_SCL_2")
		)
		(pad "2" smd circle
			(at -0.40005 0 180)
			(size 0 0)
			(layers "B.Cu" "B.Mask" "B.Paste")
			(net "I3C_SPD_DDRABCD_CPU1_LVC1_SCL")
		)
	)
)
